# T6G (Grand Teton) — schematic netlist excerpt (pin names and nets, part order shuffled) for the footprints in the layout excerpt that follows; sources: Cadence DE-HDL packaged netlist, KiCad conversion of 04192023_DAF0TMB3IC0_F0TG_MB_C_brd_V02_OCP.brd

J23  SCONN288_DDR506112002KQ  IO  pkg DDR288S_1-1VXC  page 91
  VIN_BULK0  = P12V_MEM_CPU0
  RFU0  = NC
  VIN_MGMT  = P3V3_AUX
  HSCL  = I3C_SPD_DDRF_CPU0_SCL
  HSDA  = I3C_SPD_DDRF_CPU0_SDA
  VSS0  = GND
  DQ0_A  = M_F_CPU0_SA_DQ<0>
  VSS1  = GND
  DQ1_A  = M_F_CPU0_SA_DQ<1>
  VSS2  = GND
  DQS0_A_T  = M_F_CPU0_SA_DQS_DP<0>
  DQS0_A_C  = M_F_CPU0_SA_DQS_DN<0>
  VSS3  = GND
  DQ4_A  = M_F_CPU0_SA_DQ<4>
  VSS4  = GND
  DQ5_A  = M_F_CPU0_SA_DQ<5>
  VSS5  = GND
  DQ8_A  = M_F_CPU0_SA_DQ<8>
  VSS6  = GND
  DQ9_A  = M_F_CPU0_SA_DQ<9>
  VSS7  = GND
  DQS1_A_T  = M_F_CPU0_SA_DQS_DP<1>
  DQS1_A_C  = M_F_CPU0_SA_DQS_DN<1>
  VSS8  = GND
  DQ12_A  = M_F_CPU0_SA_DQ<12>
  VSS9  = GND
  DQ13_A  = M_F_CPU0_SA_DQ<13>
  VSS10  = GND
  DQ16_A  = M_F_CPU0_SA_DQ<16>
  VSS11  = GND
  DQ17_A  = M_F_CPU0_SA_DQ<17>
  VSS12  = GND
  DQS2_A_T  = M_F_CPU0_SA_DQS_DP<2>
  DQS2_A_C  = M_F_CPU0_SA_DQS_DN<2>
  VSS13  = GND
  DQ20_A  = M_F_CPU0_SA_DQ<20>
  VSS14  = GND
  DQ21_A  = M_F_CPU0_SA_DQ<21>
  VSS15  = GND
  DQ24_A  = M_F_CPU0_SA_DQ<24>
  VSS16  = GND
  DQ25_A  = M_F_CPU0_SA_DQ<25>
  VSS17  = GND
  DQS3_A_T  = M_F_CPU0_SA_DQS_DP<3>
  DQS3_A_C  = M_F_CPU0_SA_DQS_DN<3>
  VSS18  = GND
  DQ28_A  = M_F_CPU0_SA_DQ<28>
  VSS19  = GND
  DQ29_A  = M_F_CPU0_SA_DQ<29>
  VSS20  = GND
  CB0_A  = M_F_CPU0_SA_CB<0>
  VSS21  = GND
  CB1_A  = M_F_CPU0_SA_CB<1>
  VSS22  = GND
  DQS4_A_T  = M_F_CPU0_SA_DQS_DP<4>
  DQS4_A_C  = M_F_CPU0_SA_DQS_DN<4>
  VSS23  = GND
  CB4_A  = M_F_CPU0_SA_CB<4>
  VSS24  = GND
  CB5_A  = M_F_CPU0_SA_CB<5>
  VSS25  = GND
  ALERT_N  = M_F_CPU0_ALERT_N
  VSS26  = GND
  CS0_A_N  = M_F_CPU0_SA_CS_N<0>
  VSS27  = GND
  CA0_A  = M_F_CPU0_SA_CA<0>
  VSS28  = GND
  CA2_A  = M_F_CPU0_SA_CA<2>
  VSS29  = GND
  CA4_A  = M_F_CPU0_SA_CA<4>
  VSS30  = GND
  CA6_A  = M_F_CPU0_SA_CA<6>
  VSS31  = GND
  PAR_A  = M_F_CPU0_SA_PAR
  VSS32  = GND
  CA0_B  = M_F_CPU0_SB_CA<0>
  VSS33  = GND
  CA2_B  = M_F_CPU0_SB_CA<2>
  VSS34  = GND
  CA4_B  = M_F_CPU0_SB_CA<4>
  VSS35  = GND
  CA6_B  = M_F_CPU0_SB_CA<6>
  VSS36  = GND
  CS0_B_N  = M_F_CPU0_SB_CS_N<0>
  VSS37  = GND
  \lbd||rsp_a_n\  = M_F_CPU0_SA_RSP<0>
  \lbs||rsp_b_n\  = M_F_CPU0_SB_RSP<0>
  VSS38  = GND
  CB4_B  = M_F_CPU0_SB_CB<4>
  VSS39  = GND
  CB5_B  = M_F_CPU0_SB_CB<5>
  VSS40  = GND
  \dqs9_b_t||tdqs9_b_t||dbi4_b_n\  = M_F_CPU0_SB_DQS_DP<9>
  \dqs9_b_c||tdqs9_b_c\  = M_F_CPU0_SB_DQS_DN<9>
  VSS41  = GND
  CB0_B  = M_F_CPU0_SB_CB<0>
  VSS42  = GND
  CB1_B  = M_F_CPU0_SB_CB<1>
  VSS43  = GND
  DQ0_B  = M_F_CPU0_SB_DQ<0>
  VSS44  = GND
  DQ1_B  = M_F_CPU0_SB_DQ<1>
  VSS45  = GND
  DQS0_B_T  = M_F_CPU0_SB_DQS_DP<0>
  DQS0_B_C  = M_F_CPU0_SB_DQS_DN<0>
  VSS46  = GND
  DQ4_B  = M_F_CPU0_SB_DQ<4>
  VSS47  = GND
  DQ5_B  = M_F_CPU0_SB_DQ<5>
  VSS48  = GND
  DQ8_B  = M_F_CPU0_SB_DQ<8>
  VSS49  = GND
  DQ9_B  = M_F_CPU0_SB_DQ<9>
  VSS50  = GND
  DQS1_B_T  = M_F_CPU0_SB_DQS_DP<1>
  DQS1_B_C  = M_F_CPU0_SB_DQS_DN<1>
  VSS51  = GND
  DQ12_B  = M_F_CPU0_SB_DQ<12>
  VSS52  = GND
  DQ13_B  = M_F_CPU0_SB_DQ<13>
  VSS53  = GND
  DQ16_B  = M_F_CPU0_SB_DQ<16>
  VSS54  = GND
  DQ17_B  = M_F_CPU0_SB_DQ<17>
  VSS55  = GND
  DQS2_B_T  = M_F_CPU0_SB_DQS_DP<2>
  DQS2_B_C  = M_F_CPU0_SB_DQS_DN<2>
  VSS56  = GND
  DQ20_B  = M_F_CPU0_SB_DQ<20>
  VSS57  = GND
  DQ21_B  = M_F_CPU0_SB_DQ<21>
  VSS58  = GND
  DQ24_B  = M_F_CPU0_SB_DQ<24>
  VSS59  = GND
  DQ25_B  = M_F_CPU0_SB_DQ<25>
  VSS60  = GND
  DQS3_B_T  = M_F_CPU0_SB_DQS_DP<3>
  DQS3_B_C  = M_F_CPU0_SB_DQS_DN<3>
  VSS61  = GND
  DQ28_B  = M_F_CPU0_SB_DQ<28>
  VSS62  = GND
  DQ29_B  = M_F_CPU0_SB_DQ<29>
  VSS63  = GND
  RFU1  = NC
  VIN_BULK1  = P12V_MEM_CPU0
  VIN_BULK2  = P12V_MEM_CPU0
  \pwr_good||fail_n\  = PWRGD_CHF_CPU0_DIMM
  HAS  = PD_CHF_CPU0_DIMM_SAA
  RFU2  = NC
  RFU3  = NC
  VSS64  = GND
  DQ2_A  = M_F_CPU0_SA_DQ<2>
  VSS65  = GND
  DQ3_A  = M_F_CPU0_SA_DQ<3>
  VSS66  = GND
  \dqs5_a_c||tdqs5_a_c||dqs5_a_t||tdqs5_a_t\  = M_F_CPU0_SA_DQS_DN<5>
  \dqs5_a_t||tdqs5_a_t\  = M_F_CPU0_SA_DQS_DP<5>
  VSS67  = GND
  DQ6_A  = M_F_CPU0_SA_DQ<6>
  VSS68  = GND
  DQ7_A  = M_F_CPU0_SA_DQ<7>
  VSS69  = GND
  DQ10_A  = M_F_CPU0_SA_DQ<10>
  VSS70  = GND
  DQ11_A  = M_F_CPU0_SA_DQ<11>
  VSS71  = GND
  \dqs6_a_c||tdqs6_a_c||dqs6_a_t||tdqs6_a_t\  = M_F_CPU0_SA_DQS_DN<6>
  \dqs6_a_t||tdqs6_a_t\  = M_F_CPU0_SA_DQS_DP<6>
  VSS72  = GND
  DQ14_A  = M_F_CPU0_SA_DQ<14>
  VSS73  = GND
  DQ15_A  = M_F_CPU0_SA_DQ<15>
  VSS74  = GND
  DQ18_A  = M_F_CPU0_SA_DQ<18>
  VSS75  = GND
  DQ19_A  = M_F_CPU0_SA_DQ<19>
  VSS76  = GND
  \dqs7_a_c||tdqs7_a_c\  = M_F_CPU0_SA_DQS_DN<7>
  \dqs7_a_t||tdqs7_a_t\  = M_F_CPU0_SA_DQS_DP<7>
  VSS77  = GND
  DQ22_A  = M_F_CPU0_SA_DQ<22>
  VSS78  = GND
  DQ23_A  = M_F_CPU0_SA_DQ<23>
  VSS79  = GND
  DQ26_A  = M_F_CPU0_SA_DQ<26>
  VSS80  = GND
  DQ27_A  = M_F_CPU0_SA_DQ<27>
  VSS81  = GND
  \dqs8_a_c||tdqs8_a_c\  = M_F_CPU0_SA_DQS_DN<8>
  \dqs8_a_t||tdqs8_a_t\  = M_F_CPU0_SA_DQS_DP<8>
  VSS82  = GND
  DQ30_A  = M_F_CPU0_SA_DQ<30>
  VSS83  = GND
  DQ31_A  = M_F_CPU0_SA_DQ<31>
  VSS84  = GND
  CB2_A  = M_F_CPU0_SA_CB<2>
  VSS85  = GND
  CB3_A  = M_F_CPU0_SA_CB<3>
  VSS86  = GND
  \dqs9_a_c||tdqs9_a_c\  = M_F_CPU0_SA_DQS_DN<9>
  \dqs9_a_t||tdqs9_a_t\  = M_F_CPU0_SA_DQS_DP<9>
  VSS87  = GND
  CB6_A  = M_F_CPU0_SA_CB<6>
  VSS88  = GND
  CB7_A  = M_F_CPU0_SA_CB<7>
  VSS89  = GND
  RESET_N  = M_F_CPU0_RESET_N
  VSS90  = GND
  CS1_A_N  = M_F_CPU0_SA_CS_N<1>
  VSS91  = GND
  CA1_A  = M_F_CPU0_SA_CA<1>
  VSS92  = GND
  CA3_A  = M_F_CPU0_SA_CA<3>
  VSS93  = GND
  CA5_A  = M_F_CPU0_SA_CA<5>
  VSS94  = GND
  CK_T  = M_F_CPU0_CLK_DP<0>
  CK_C  = M_F_CPU0_CLK_DN<0>
  VSS95  = GND
  RFU4  = NC
  CA1_B  = M_F_CPU0_SB_CA<1>
  VSS96  = GND
  CA3_B  = M_F_CPU0_SB_CA<3>
  VSS97  = GND
  CA5_B  = M_F_CPU0_SB_CA<5>
  VSS98  = GND
  PAR_B  = M_F_CPU0_SB_PAR
  VSS99  = GND
  CS1_B_N  = M_F_CPU0_SB_CS_N<1>
  VSS100  = GND
  RFU5  = NC
  RFU6  = NC
  VSS101  = GND
  CB6_B  = M_F_CPU0_SB_CB<6>
  VSS102  = GND
  CB7_B  = M_F_CPU0_SB_CB<7>
  VSS103  = GND
  DQS4_B_C  = M_F_CPU0_SB_DQS_DN<4>
  DQS4_B_T  = M_F_CPU0_SB_DQS_DP<4>
  VSS104  = GND
  CB2_B  = M_F_CPU0_SB_CB<2>
  VSS105  = GND
  CB3_B  = M_F_CPU0_SB_CB<3>
  VSS106  = GND
  DQ2_B  = M_F_CPU0_SB_DQ<2>
  VSS107  = GND
  DQ3_B  = M_F_CPU0_SB_DQ<3>
  VSS108  = GND
  \dqs5_b_c||tdqs5_b_c\  = M_F_CPU0_SB_DQS_DN<5>
  \dqs5_b_t||tdqs5_b_t\  = M_F_CPU0_SB_DQS_DP<5>
  VSS109  = GND
  DQ6_B  = M_F_CPU0_SB_DQ<6>
  VSS110  = GND
  DQ7_B  = M_F_CPU0_SB_DQ<7>
  VSS111  = GND
  DQ10_B  = M_F_CPU0_SB_DQ<10>
  VSS112  = GND
  DQ11_B  = M_F_CPU0_SB_DQ<11>
  VSS113  = GND
  \dqs6_b_c||tdqs6_b_c\  = M_F_CPU0_SB_DQS_DN<6>
  \dqs6_b_t||tdqs6_b_t\  = M_F_CPU0_SB_DQS_DP<6>
  VSS114  = GND
  DQ14_B  = M_F_CPU0_SB_DQ<14>
  VSS115  = GND
  DQ15_B  = M_F_CPU0_SB_DQ<15>
  VSS116  = GND
  DQ18_B  = M_F_CPU0_SB_DQ<18>
  VSS117  = GND
  DQ19_B  = M_F_CPU0_SB_DQ<19>
  VSS118  = GND
  \dqs7_b_c||tdqs7_b_c\  = M_F_CPU0_SB_DQS_DN<7>
  \dqs7_b_t||tdqs7_b_t\  = M_F_CPU0_SB_DQS_DP<7>
  VSS119  = GND
  DQ22_B  = M_F_CPU0_SB_DQ<22>
  VSS120  = GND
  DQ23_B  = M_F_CPU0_SB_DQ<23>
  VSS121  = GND
  DQ26_B  = M_F_CPU0_SB_DQ<26>
  VSS122  = GND
  DQ27_B  = M_F_CPU0_SB_DQ<27>
  VSS123  = GND
  \dqs8_b_c||tdqs8_b_c\  = M_F_CPU0_SB_DQS_DN<8>
  \dqs8_b_t||tdqs8_b_t\  = M_F_CPU0_SB_DQS_DP<8>
  VSS124  = GND
  DQ30_B  = M_F_CPU0_SB_DQ<30>
  VSS125  = GND
  DQ31_B  = M_F_CPU0_SB_DQ<31>
  VSS126  = GND
  G1  = GND
  G2  = GND
  G3  = GND

(kicad_pcb
	(version 20260206)
	(generator "pcbnew")
	(generator_version "10.0")
	(general
		(thickness 1.6)
		(legacy_teardrops no)
	)
	(paper "A4")
	(title_block
		(title "04192023_DAF0TMB3IC0_F0TG_MB_C_brd_V02_OCP.brd")
		(comment 1 "Grand Teton / footprint 2449 of 8354 (J23), pads 231-276 of 291")
	)
	(layers
		(0 "F.Cu" signal "TOP")
		(4 "In1.Cu" signal "GND")
		(6 "In2.Cu" signal "IN1")
		(8 "In3.Cu" signal "GND1")
		(10 "In4.Cu" signal "IN2")
		(12 "In5.Cu" signal "GND2")
		(14 "In6.Cu" signal "IN3")
		(16 "In7.Cu" signal "GND3")
		(18 "In8.Cu" signal "VCC")
		(20 "In9.Cu" signal "VCC1")
		(22 "In10.Cu" signal "GND4")
		(24 "In11.Cu" signal "IN4")
		(26 "In12.Cu" signal "GND5")
		(28 "In13.Cu" signal "IN5")
		(30 "In14.Cu" signal "GND6")
		(32 "In15.Cu" signal "IN6")
		(34 "In16.Cu" signal "GND7")
		(2 "B.Cu" signal "BOTTOM")
		(9 "F.Adhes" user "F.Adhesive")
		(11 "B.Adhes" user "B.Adhesive")
		(13 "F.Paste" user "Package Geometry/Pastemask Top")
		(15 "B.Paste" user "Package Geometry/Pastemask Bottom")
		(5 "F.SilkS" user "Ref Des/Silkscreen Top")
		(7 "B.SilkS" user "Ref Des/Silkscreen Bottom")
		(1 "F.Mask" user "Board Geometry/Soldermask Top")
		(3 "B.Mask" user "Board Geometry/Soldermask Bottom")
		(17 "Dwgs.User" user "User.Drawings")
		(19 "Cmts.User" user "User.Comments")
		(21 "Eco1.User" user "User.Eco1")
		(23 "Eco2.User" user "User.Eco2")
		(25 "Edge.Cuts" user "Board Geometry/Outline")
		(27 "Margin" user)
		(31 "F.CrtYd" user "Package Geometry/Place Bound Top")
		(29 "B.CrtYd" user "Package Geometry/Place Bound Bottom")
		(35 "F.Fab" user "Ref Des/Assembly Top")
		(33 "B.Fab" user "Ref Des/Assembly Bottom")
	)
	(footprint ""
		(layer "F.Cu")
		(at 267.598144 -255.560068 180)
		(property "Reference" "J23"
			(at -2.2098 -81.984088 0)
			(unlocked yes)
			(layer "F.SilkS")
			(effects
				(font
					(size 0.7874 0.5842)
					(thickness 0.1524)
				)
			)
		)
		(property "Value" ""
			(at 0 0 180)
			(layer "F.Fab")
			(effects
				(font
					(size 1.27 1.27)
				)
			)
		)
		(duplicate_pad_numbers_are_jumpers no)
		(pad "231" smd rect
			(at 2.050034 14.875002 90)
			(size 0.519938 1.4986)
			(layers "F.Cu" "F.Mask" "F.Paste")
			(net "Net_2324")
		)
		(pad "232" smd rect
			(at 2.050034 15.724886 90)
			(size 0.519938 1.4986)
			(layers "F.Cu" "F.Mask" "F.Paste")
			(net "Net_2325")
		)
		(pad "233" smd rect
			(at 2.050034 16.575024 90)
			(size 0.519938 1.4986)
			(layers "F.Cu" "F.Mask" "F.Paste")
			(net "GND")
		)
		(pad "234" smd rect
			(at 2.050034 17.424908 90)
			(size 0.519938 1.4986)
			(layers "F.Cu" "F.Mask" "F.Paste")
			(net "M_F_CPU0_SB_CB<6>")
		)
		(pad "235" smd rect
			(at 2.050034 18.275046 90)
			(size 0.519938 1.4986)
			(layers "F.Cu" "F.Mask" "F.Paste")
			(net "GND")
		)
		(pad "236" smd rect
			(at 2.050034 19.12493 90)
			(size 0.519938 1.4986)
			(layers "F.Cu" "F.Mask" "F.Paste")
			(net "M_F_CPU0_SB_CB<7>")
		)
		(pad "237" smd rect
			(at 2.050034 19.975068 90)
			(size 0.519938 1.4986)
			(layers "F.Cu" "F.Mask" "F.Paste")
			(net "GND")
		)
		(pad "238" smd rect
			(at 2.050034 20.824952 90)
			(size 0.519938 1.4986)
			(layers "F.Cu" "F.Mask" "F.Paste")
			(net "M_F_CPU0_SB_DQS_DN<4>")
		)
		(pad "239" smd rect
			(at 2.050034 21.67509 90)
			(size 0.519938 1.4986)
			(layers "F.Cu" "F.Mask" "F.Paste")
			(net "M_F_CPU0_SB_DQS_DP<4>")
		)
		(pad "240" smd rect
			(at 2.050034 22.524974 90)
			(size 0.519938 1.4986)
			(layers "F.Cu" "F.Mask" "F.Paste")
			(net "GND")
		)
		(pad "241" smd rect
			(at 2.050034 23.375112 90)
			(size 0.519938 1.4986)
			(layers "F.Cu" "F.Mask" "F.Paste")
			(net "M_F_CPU0_SB_CB<2>")
		)
		(pad "242" smd rect
			(at 2.050034 24.224996 90)
			(size 0.519938 1.4986)
			(layers "F.Cu" "F.Mask" "F.Paste")
			(net "GND")
		)
		(pad "243" smd rect
			(at 2.050034 25.07488 90)
			(size 0.519938 1.4986)
			(layers "F.Cu" "F.Mask" "F.Paste")
			(net "M_F_CPU0_SB_CB<3>")
		)
		(pad "244" smd rect
			(at 2.050034 25.925018 90)
			(size 0.519938 1.4986)
			(layers "F.Cu" "F.Mask" "F.Paste")
			(net "GND")
		)
		(pad "245" smd rect
			(at 2.050034 26.774902 90)
			(size 0.519938 1.4986)
			(layers "F.Cu" "F.Mask" "F.Paste")
			(net "M_F_CPU0_SB_DQ<2>")
		)
		(pad "246" smd rect
			(at 2.050034 27.62504 90)
			(size 0.519938 1.4986)
			(layers "F.Cu" "F.Mask" "F.Paste")
			(net "GND")
		)
		(pad "247" smd rect
			(at 2.050034 28.474924 90)
			(size 0.519938 1.4986)
			(layers "F.Cu" "F.Mask" "F.Paste")
			(net "M_F_CPU0_SB_DQ<3>")
		)
		(pad "248" smd rect
			(at 2.050034 29.325062 90)
			(size 0.519938 1.4986)
			(layers "F.Cu" "F.Mask" "F.Paste")
			(net "GND")
		)
		(pad "249" smd rect
			(at 2.050034 30.174946 90)
			(size 0.519938 1.4986)
			(layers "F.Cu" "F.Mask" "F.Paste")
			(net "M_F_CPU0_SB_DQS_DN<5>")
		)
		(pad "250" smd rect
			(at 2.050034 31.025084 90)
			(size 0.519938 1.4986)
			(layers "F.Cu" "F.Mask" "F.Paste")
			(net "M_F_CPU0_SB_DQS_DP<5>")
		)
		(pad "251" smd rect
			(at 2.050034 31.874968 90)
			(size 0.519938 1.4986)
			(layers "F.Cu" "F.Mask" "F.Paste")
			(net "GND")
		)
		(pad "252" smd rect
			(at 2.050034 32.725106 90)
			(size 0.519938 1.4986)
			(layers "F.Cu" "F.Mask" "F.Paste")
			(net "M_F_CPU0_SB_DQ<6>")
		)
		(pad "253" smd rect
			(at 2.050034 33.57499 90)
			(size 0.519938 1.4986)
			(layers "F.Cu" "F.Mask" "F.Paste")
			(net "GND")
		)
		(pad "254" smd rect
			(at 2.050034 34.425128 90)
			(size 0.519938 1.4986)
			(layers "F.Cu" "F.Mask" "F.Paste")
			(net "M_F_CPU0_SB_DQ<7>")
		)
		(pad "255" smd rect
			(at 2.050034 35.275012 90)
			(size 0.519938 1.4986)
			(layers "F.Cu" "F.Mask" "F.Paste")
			(net "GND")
		)
		(pad "256" smd rect
			(at 2.050034 36.124896 90)
			(size 0.519938 1.4986)
			(layers "F.Cu" "F.Mask" "F.Paste")
			(net "M_F_CPU0_SB_DQ<10>")
		)
		(pad "257" smd rect
			(at 2.050034 36.975034 90)
			(size 0.519938 1.4986)
			(layers "F.Cu" "F.Mask" "F.Paste")
			(net "GND")
		)
		(pad "258" smd rect
			(at 2.050034 37.824918 90)
			(size 0.519938 1.4986)
			(layers "F.Cu" "F.Mask" "F.Paste")
			(net "M_F_CPU0_SB_DQ<11>")
		)
		(pad "259" smd rect
			(at 2.050034 38.675056 90)
			(size 0.519938 1.4986)
			(layers "F.Cu" "F.Mask" "F.Paste")
			(net "GND")
		)
		(pad "260" smd rect
			(at 2.050034 39.52494 90)
			(size 0.519938 1.4986)
			(layers "F.Cu" "F.Mask" "F.Paste")
			(net "M_F_CPU0_SB_DQS_DN<6>")
		)
		(pad "261" smd rect
			(at 2.050034 40.375078 90)
			(size 0.519938 1.4986)
			(layers "F.Cu" "F.Mask" "F.Paste")
			(net "M_F_CPU0_SB_DQS_DP<6>")
		)
		(pad "262" smd rect
			(at 2.050034 41.224962 90)
			(size 0.519938 1.4986)
			(layers "F.Cu" "F.Mask" "F.Paste")
			(net "GND")
		)
		(pad "263" smd rect
			(at 2.050034 42.0751 90)
			(size 0.519938 1.4986)
			(layers "F.Cu" "F.Mask" "F.Paste")
			(net "M_F_CPU0_SB_DQ<14>")
		)
		(pad "264" smd rect
			(at 2.050034 42.924984 90)
			(size 0.519938 1.4986)
			(layers "F.Cu" "F.Mask" "F.Paste")
			(net "GND")
		)
		(pad "265" smd rect
			(at 2.050034 43.775122 90)
			(size 0.519938 1.4986)
			(layers "F.Cu" "F.Mask" "F.Paste")
			(net "M_F_CPU0_SB_DQ<15>")
		)
		(pad "266" smd rect
			(at 2.050034 44.625006 90)
			(size 0.519938 1.4986)
			(layers "F.Cu" "F.Mask" "F.Paste")
			(net "GND")
		)
		(pad "267" smd rect
			(at 2.050034 45.47489 90)
			(size 0.519938 1.4986)
			(layers "F.Cu" "F.Mask" "F.Paste")
			(net "M_F_CPU0_SB_DQ<18>")
		)
		(pad "268" smd rect
			(at 2.050034 46.325028 90)
			(size 0.519938 1.4986)
			(layers "F.Cu" "F.Mask" "F.Paste")
			(net "GND")
		)
		(pad "269" smd rect
			(at 2.050034 47.174912 90)
			(size 0.519938 1.4986)
			(layers "F.Cu" "F.Mask" "F.Paste")
			(net "M_F_CPU0_SB_DQ<19>")
		)
		(pad "270" smd rect
			(at 2.050034 48.02505 90)
			(size 0.519938 1.4986)
			(layers "F.Cu" "F.Mask" "F.Paste")
			(net "GND")
		)
		(pad "271" smd rect
			(at 2.050034 48.874934 90)
			(size 0.519938 1.4986)
			(layers "F.Cu" "F.Mask" "F.Paste")
			(net "M_F_CPU0_SB_DQS_DN<7>")
		)
		(pad "272" smd rect
			(at 2.050034 49.725072 90)
			(size 0.519938 1.4986)
			(layers "F.Cu" "F.Mask" "F.Paste")
			(net "M_F_CPU0_SB_DQS_DP<7>")
		)
		(pad "273" smd rect
			(at 2.050034 50.574956 90)
			(size 0.519938 1.4986)
			(layers "F.Cu" "F.Mask" "F.Paste")
			(net "GND")
		)
		(pad "274" smd rect
			(at 2.050034 51.425094 90)
			(size 0.519938 1.4986)
			(layers "F.Cu" "F.Mask" "F.Paste")
			(net "M_F_CPU0_SB_DQ<22>")
		)
		(pad "275" smd rect
			(at 2.050034 52.274978 90)
			(size 0.519938 1.4986)
			(layers "F.Cu" "F.Mask" "F.Paste")
			(net "GND")
		)
		(pad "276" smd rect
			(at 2.050034 53.125116 90)
			(size 0.519938 1.4986)
			(layers "F.Cu" "F.Mask" "F.Paste")
			(net "M_F_CPU0_SB_DQ<23>")
		)
	)
)
